# BASEBOARD_FAB2 (Tioga Pass) — schematic netlist excerpt (pin names and nets, part order shuffled) for the footprints in the layout excerpt that follows; sources: Cadence DE-HDL packaged netlist, KiCad conversion of Wiwynn_Tioga_Pass_MB.brd

C7E8  CAP  10UF 16V 10% X6S  pkg 0805  page 198 : A = P12V ; B = GND
C1C9  CAP_A  0.1UF 16V 10% X7R  pkg 0402V  page 206 : A = VR_PVCCIN_CPU1_VDD ; B = GND

(kicad_pcb
	(version 20260206)
	(generator "pcbnew")
	(generator_version "10.0")
	(general
		(thickness 1.6)
		(legacy_teardrops no)
	)
	(paper "A4")
	(title_block
		(title "Wiwynn_Tioga_Pass_MB.brd")
		(comment 1 "Tioga Pass / footprints 885-886 of 4770")
	)
	(layers
		(0 "F.Cu" signal "TOP")
		(4 "In1.Cu" signal "L2GND")
		(6 "In2.Cu" signal "L3")
		(8 "In3.Cu" signal "L4GND")
		(10 "In4.Cu" signal "L5")
		(12 "In5.Cu" signal "L6GND")
		(14 "In6.Cu" signal "L7VCC")
		(16 "In7.Cu" signal "L8VCC")
		(18 "In8.Cu" signal "L9GND")
		(20 "In9.Cu" signal "L10")
		(22 "In10.Cu" signal "L11GND")
		(24 "In11.Cu" signal "L12")
		(26 "In12.Cu" signal "L13GND")
		(2 "B.Cu" signal "BOTTOM")
		(9 "F.Adhes" user "F.Adhesive")
		(11 "B.Adhes" user "B.Adhesive")
		(13 "F.Paste" user "Package Geometry/Pastemask Top")
		(15 "B.Paste" user "Package Geometry/Pastemask Bottom")
		(5 "F.SilkS" user "Ref Des/Silkscreen Top")
		(7 "B.SilkS" user "Ref Des/Silkscreen Bottom")
		(1 "F.Mask" user "Board Geometry/Soldermask Top")
		(3 "B.Mask" user "Board Geometry/Soldermask Bottom")
		(17 "Dwgs.User" user "User.Drawings")
		(19 "Cmts.User" user "User.Comments")
		(21 "Eco1.User" user "User.Eco1")
		(23 "Eco2.User" user "User.Eco2")
		(25 "Edge.Cuts" user "Board Geometry/Outline")
		(27 "Margin" user)
		(31 "F.CrtYd" user "Package Geometry/Place Bound Top")
		(29 "B.CrtYd" user "Package Geometry/Place Bound Bottom")
		(35 "F.Fab" user "Ref Des/Assembly Top")
		(33 "B.Fab" user "Ref Des/Assembly Bottom")
	)
	(footprint ""
		(layer "F.Cu")
		(at 496.581684 -19.373088 90)
		(property "Reference" "C7E8"
			(at 0 0 90)
			(layer "F.SilkS")
			(hide yes)
			(effects
				(font
					(size 1.27 1.27)
				)
			)
		)
		(property "Value" ""
			(at 0 0 90)
			(layer "F.Fab")
			(effects
				(font
					(size 1.27 1.27)
				)
			)
		)
		(duplicate_pad_numbers_are_jumpers no)
		(fp_rect
			(start -0.7239 1.9939)
			(end 0.7239 -0.2159)
			(stroke
				(width 0)
				(type default)
			)
			(fill no)
			(layer "F.CrtYd")
		)
		(fp_line
			(start 0.7239 -0.2159)
			(end -0.7239 -0.2159)
			(stroke
				(width 0.1)
				(type default)
			)
			(layer "F.Fab")
		)
		(fp_line
			(start -0.7239 -0.2159)
			(end -0.7239 1.9939)
			(stroke
				(width 0.1)
				(type default)
			)
			(layer "F.Fab")
		)
		(fp_line
			(start 0.7239 1.9939)
			(end 0.7239 -0.2159)
			(stroke
				(width 0.1)
				(type default)
			)
			(layer "F.Fab")
		)
		(fp_line
			(start -0.7239 1.9939)
			(end 0.7239 1.9939)
			(stroke
				(width 0.1)
				(type default)
			)
			(layer "F.Fab")
		)
		(pad "1" smd rect
			(at 0 0 90)
			(size 1.27 1.016)
			(layers "F.Cu" "F.Mask" "F.Paste")
			(net "P12V")
		)
		(pad "2" smd rect
			(at 0 1.778 90)
			(size 1.27 1.016)
			(layers "F.Cu" "F.Mask" "F.Paste")
			(net "GND")
		)
		(zone
			(layer "F.Cu")
			(hatch none 0.5)
			(connect_pads
				(clearance 0)
			)
			(min_thickness 0.25)
			(keepout
				(tracks not_allowed)
				(vias allowed)
				(pads allowed)
				(copperpour not_allowed)
				(footprints allowed)
			)
			(placement
				(enabled no)
				(sheetname "")
			)
			(fill
				(thermal_gap 0.5)
				(thermal_bridge_width 0.5)
				(island_removal_mode 0)
			)
			(polygon
				(pts
					(xy 497.851684 -18.738088) (xy 497.851684 -20.008088) (xy 497.089684 -20.008088) (xy 497.089684 -18.738088)
				)
			)
		)
	)
	(footprint ""
		(layer "F.Cu")
		(at 16.383 -97.8916 -90)
		(property "Reference" "C1C9"
			(at 0 0 270)
			(layer "F.SilkS")
			(hide yes)
			(effects
				(font
					(size 1.27 1.27)
				)
			)
		)
		(property "Value" ""
			(at 0 0 270)
			(layer "F.Fab")
			(effects
				(font
					(size 1.27 1.27)
				)
			)
		)
		(duplicate_pad_numbers_are_jumpers no)
		(fp_rect
			(start 0.3048 0.9906)
			(end -0.3048 -0.1016)
			(stroke
				(width 0)
				(type default)
			)
			(fill no)
			(layer "F.CrtYd")
		)
		(fp_line
			(start -0.3048 0.9906)
			(end 0.3048 0.9906)
			(stroke
				(width 0.1)
				(type default)
			)
			(layer "F.Fab")
		)
		(fp_line
			(start 0.3048 0.9906)
			(end 0.3048 -0.1016)
			(stroke
				(width 0.1)
				(type default)
			)
			(layer "F.Fab")
		)
		(fp_line
			(start -0.3048 -0.1016)
			(end -0.3048 0.9906)
			(stroke
				(width 0.1)
				(type default)
			)
			(layer "F.Fab")
		)
		(fp_line
			(start 0.3048 -0.1016)
			(end -0.3048 -0.1016)
			(stroke
				(width 0.1)
				(type default)
			)
			(layer "F.Fab")
		)
		(pad "1" smd rect
			(at 0 0 270)
			(size 0.508 0.508)
			(layers "F.Cu" "F.Mask" "F.Paste")
			(net "VR_PVCCIN_CPU1_VDD")
		)
		(pad "2" smd rect
			(at 0 0.889 270)
			(size 0.508 0.508)
			(layers "F.Cu" "F.Mask" "F.Paste")
			(net "GND")
		)
		(zone
			(layer "F.Cu")
			(hatch none 0.5)
			(connect_pads
				(clearance 0)
			)
			(min_thickness 0.25)
			(keepout
				(tracks not_allowed)
				(vias allowed)
				(pads allowed)
				(copperpour not_allowed)
				(footprints allowed)
			)
			(placement
				(enabled no)
				(sheetname "")
			)
			(fill
				(thermal_gap 0.5)
				(thermal_bridge_width 0.5)
				(island_removal_mode 0)
			)
			(polygon
				(pts
					(xy 15.748 -97.6376) (xy 16.129 -97.6376) (xy 16.129 -98.1456) (xy 15.748 -98.1456)
				)
			)
		)
		(zone
			(layer "F.Cu")
			(hatch none 0.5)
			(connect_pads
				(clearance 0)
			)
			(min_thickness 0.25)
			(keepout
				(tracks allowed)
				(vias not_allowed)
				(pads allowed)
				(copperpour not_allowed)
				(footprints allowed)
			)
			(placement
				(enabled no)
				(sheetname "")
			)
			(fill
				(thermal_gap 0.5)
				(thermal_bridge_width 0.5)
				(island_removal_mode 0)
			)
			(polygon
				(pts
					(xy 15.748 -97.6376) (xy 16.129 -97.6376) (xy 16.129 -98.1456) (xy 15.748 -98.1456)
				)
			)
		)
	)
)
